FILE_TYPE = CONNECTIVITY;
{Allegro Design Entry HDL 17.2-2016 S081 (4005846) 1/11/2022}
"PAGE_NUMBER" = 226;
0"NC";
1"P3V3_AUX\g";
2"P3V3_AUX\g";
3"P3V3_AUX\g";
4"P3V3_AUX\g";
5"P1V05_PCH_AUX\g";
6"P3V3_AUX\g";
7"P3V3_AUX\g";
8"P3V3_AUX\g";
9"P3V3_AUX\g";
10"P3V3_AUX\g";
11"GND\g";
12"GND\g";
13"GND\g";
14"GND\g";
15"GND\g";
16"GND\g";
17"GND\g";
18"GND\g";
19"GND\g";
20"GND\g";
21"GND\g";
22"GND\g";
23"FM_JTAG_BMC_MUX_SEL";
24"JTAG_BMC_PLD_TDO"CDS_PHYS_NET_NAME"JTAG_BMC_PLD_TDO";
25"JTAG_BMC_DBP_TDI"CDS_PHYS_NET_NAME"JTAG_BMC_DBP_TDI";
26"JTAG_BMC_DBP_TDO"CDS_PHYS_NET_NAME"JTAG_BMC_DBP_TDO";
27"JTAG_BMC_PLD_TDI"CDS_PHYS_NET_NAME"JTAG_BMC_PLD_TDI";
28"JTAG_BMC_DBP_TDO";
29"JTAG_BMC_SW_TDI";
30"JTAG_BMC_SW_TCK";
31"JTAG_BMC_SW_TMS";
32"JTAG_BMC_SW_TDO";
33"TP_JTAG_BMC_A0";
34"JTAG_BMC_PLD_TCK"CDS_PHYS_NET_NAME"JTAG_BMC_PLD_TCK";
35"JTAG_BMC_PLD_TMS"CDS_PHYS_NET_NAME"JTAG_BMC_PLD_TMS";
36"JTAG_BMC_DBP_TCK"CDS_PHYS_NET_NAME"JTAG_BMC_DBP_TCK";
37"JTAG_BMC_DBP_TMS"CDS_PHYS_NET_NAME"JTAG_BMC_DBP_TMS";
38"JTAG_DBP_PRDY_N";
39"JTAG_DBP_TDO";
40"JTAG_DBP_PRDY_R_N";
41"JTAG_DBP_FB_TDO";
42"JTAG_DBP_PREQ_N";
43"FM_CPU_FBRK_DEBUG_N";
44"JTAG_DBP_TDI";
45"JTAG_DBP_TMS";
46"JTAG_DBP_PREQ_R_N";
47"JTAG_DBP_FB_TDI";
48"JTAG_DBP_FB_TMS";
49"PD_GTL2014_BMC_JTAG_DIR_2";
50"JTAG_DBP_BMC_PRDY_R1_N";
51"TP_JTAG_BMC_A2";
52"JTAG_BMC_DBP_TDO_R";
53"PD_JTAG_DBP_B2";
54"PD_JTAG_DBP_B0";
55"PD_GTL2014_BMC_JTAG_VREF_1";
56"JTAG_DBP_BMC_PREQ_R1_N";
57"JTAG_BMC_DBP_TDI_R";
58"JTAG_BMC_DBP_TMS_R";
59"JTAG_DBP_BMC_PRDY_R_N";
60"PU_GTL2014_BMC_JTAG_DIR_1";
61"JTAG_DBP_BMC_PREQ_R_N";
62"JTAG_BMC_DBP_TDI";
63"FM_BMC_CPU_FBRK_OUT_N";
64"JTAG_BMC_DBP_TMS";
65"P0V7_JTAG_VREF_2";
66"JTAG_DBP_BMC_PRDY_N";
67"JTAG_BMC_DBP_PREQ_N";
%"Q_RES"
"2","(-7700,3575)","0","pure_quanta","I1";
;
PART_NUMBER"CS21002FB06"
VALUE"1K"
TOLERANCE"1%"
WATTAGE"1/16W"
PACK_TYPE"0402LF"
MATERIAL"CHIP"
$LOCATION"R1383"
CDS_LIB"pure_quanta"
CDS_LOCATION"R1383"
$SEC"1"
CDS_SEC"1";
"A"
$PN"1"10;
"B"
$PN"2"67;
%"Q_RES"
"1","(-9400,3400)","0","pure_quanta","I10";
;
PART_NUMBER"CS21002FB06"
WATTAGE"1/16W"
VALUE"1K"
TOLERANCE"1%"
MATERIAL"CHIP"
PACK_TYPE"0402LF"
$LOCATION"R1347"
CDS_LIB"pure_quanta"
$LOCATION"R1347"
CDS_LOCATION"R1347"
$SEC"1"
CDS_SEC"1";
"B"
$PN"2"21;
"A"
$PN"1"55;
%"Q_RES"
"2","(-10100,3750)","0","pure_quanta","I11";
;
PART_NUMBER"CS21002FB06"
MATERIAL"CHIP"
PACK_TYPE"0402LF"
WATTAGE"1/16W"
VALUE"1K"
TOLERANCE"1%"
$LOCATION"R3055"
CDS_LIB"pure_quanta"
CDS_LOCATION"R3055"
$SEC"1"
CDS_SEC"1";
"A"
$PN"1"6;
"B"
$PN"2"60;
%"Q_RES"
"1","(-9850,3050)","0","pure_quanta","I12";
;
PART_NUMBER"CS03322FB03"
PACK_TYPE"0402LF"
WATTAGE"1/16W"
VALUE"33.2"
TOLERANCE"1%"
MATERIAL"CHIP"
$LOCATION"R3057"
CDS_LIB"pure_quanta"
CDS_LOCATION"R3057"
$SEC"1"
CDS_SEC"1";
"B"
$PN"2"67;
"A"
$PN"1"56;
%"Q_RES"
"1","(-9850,3150)","0","pure_quanta","I13";
;
PART_NUMBER"CS00002JB13"
MATERIAL"CHIP"
TOLERANCE"5%"
VALUE"0"
$LOCATION"R1345"
CDS_LIB"pure_quanta"
PACK_TYPE"0402LF"
WATTAGE"1/16W"
$LOCATION"R1345"
CDS_LOCATION"R1345"
$SEC"1"
CDS_SEC"1";
"B"
$PN"2"62;
"A"
$PN"1"57;
%"Q_RES"
"1","(-9850,3200)","0","pure_quanta","I14";
;
PART_NUMBER"CS00002JB13"
VALUE"0"
MATERIAL"CHIP"
TOLERANCE"5%"
$LOCATION"R1184"
WATTAGE"1/16W"
PACK_TYPE"0402LF"
CDS_LIB"pure_quanta"
$LOCATION"R1184"
CDS_LOCATION"R1184"
$SEC"1"
CDS_SEC"1";
"B"
$PN"2"64;
"A"
$PN"1"58;
%"UNIVERSAL_POWER"
"1","(-10825,4025)","0","logical_power","I15";
;
HDL_POWER"P3V3_AUX"
CDS_LIB"logical_power";
"A"4;
%"Q_CAP"
"1","(-10675,3775)","0","pure_quanta","I16";
;
PART_NUMBER"CH5104KEB02"
VALUE"1UF"
VOLTAGE"25V"
MATERIAL"X6S"
TOLERANCE"10%"
PACK_TYPE"C0402"
$LOCATION"C1291"
CDS_LIB"pure_quanta"
$LOCATION"C1291"
CDS_LOCATION"C1291"
$SEC"1"
CDS_SEC"1";
"B"
$PN"2"19;
"A"
$PN"1"4;
%"UNIVERSAL_GND"
"1","(-10675,3550)","0","logical_power","I17";
;
CDS_LIB"logical_power"
HDL_POWER"GND";
"A"19;
%"GTL2014PW"
"1","(-11325,3150)","2","pure_quanta","I18";
;
PART_NUMBER"AL002014K01"
VALUE"GTL2014PW"
MATERIAL"IC"
PART_TYPE"SMLF"
$LOCATION"U84"
NEEDS_NO_SIZE"TRUE"
CDS_LMAN_SYM_OUTLINE"-250,350,250,-350"
CDS_LIB"pure_quanta"
SEC_TYPE""
$LOCATION"U84"
CDS_LOCATION"U84"
SEC"1";
"VCC"
$PN"14"4;
"VREF"
$PN"4"55;
"DIR"
$PN"1"60;
"A0"
$PN"13"56;
"A1"
$PN"12"63;
"A2"
$PN"10"57;
"A3"
$PN"9"58;
"GND_0"
$PN"7"18;
"GND_1"
$PN"8"18;
"GND_2"
$PN"11"18;
"B3"
$PN"6"48;
"B2"
$PN"5"47;
"B1"
$PN"3"43;
"B0"
$PN"2"46;
%"UNIVERSAL_GND"
"1","(-11850,2750)","0","logical_power","I19";
;
HDL_POWER"GND"
CDS_LIB"logical_power";
"A"18;
%"Q_RES"
"2","(-8100,2000)","0","pure_quanta","I20";
;
PART_NUMBER"CS21002FB06"
VALUE"1K"
TOLERANCE"1%"
WATTAGE"1/16W"
MATERIAL"CHIP"
PACK_TYPE"0402LF"
$LOCATION"R1382"
CDS_LIB"pure_quanta"
CDS_LOCATION"R1382"
$SEC"1"
CDS_SEC"1";
"A"
$PN"1"7;
"B"
$PN"2"66;
%"Q_CAP"
"1","(-7675,300)","0","pure_quanta","I27";
;
PART_NUMBER"CH4104K1B00"
PACK_TYPE"0402"
TOLERANCE"10%"
MATERIAL"X7R"
VOLTAGE"25V"
VALUE"0.1UF"
$LOCATION"C1322"
CDS_LIB"pure_quanta"
CDS_LOCATION"C1322"
$SEC"1"
CDS_SEC"1";
"B"
$PN"2"22;
"A"
$PN"1"9;
%"UNIVERSAL_POWER"
"1","(-7825,575)","0","logical_power","I28";
;
HDL_POWER"P3V3_AUX"
CDS_LIB"logical_power";
"A"9;
%"UNIVERSAL_GND"
"1","(-7675,100)","0","logical_power","I29";
;
HDL_POWER"GND"
CDS_LIB"logical_power";
"A"22;
%"UNIVERSAL_POWER"
"1","(-8325,2400)","0","logical_power","I30";
;
HDL_POWER"P3V3_AUX"
CDS_LIB"logical_power";
"A"7;
%"Q_RES"
"2","(-8325,2000)","0","pure_quanta","I31";
;
PART_NUMBER"CS21002FB06"
WATTAGE"1/16W"
TOLERANCE"1%"
VALUE"1K"
MATERIAL"CHIP"
PACK_TYPE"0402LF"
$LOCATION"R1380"
CDS_LIB"pure_quanta"
CDS_LOCATION"R1380"
$SEC"1"
CDS_SEC"1";
"A"
$PN"1"7;
"B"
$PN"2"28;
%"UNIVERSAL_GND"
"1","(-9000,1650)","2","logical_power","I32";
;
HDL_POWER"GND"
CDS_LIB"logical_power";
"A"20;
%"Q_RES"
"1","(-9450,1825)","0","pure_quanta","I34";
;
PART_NUMBER"CS11002FB07"
WATTAGE"1/16W"
MATERIAL"CHIP"
TOLERANCE"1%"
VALUE"100"
PACK_TYPE"0402LF"
$LOCATION"R1346"
CDS_LIB"pure_quanta"
CDS_LOCATION"R1346"
$SEC"1"
CDS_SEC"1";
"B"
$PN"2"20;
"A"
$PN"1"65;
%"Q_RES"
"1","(-9950,1525)","0","pure_quanta","I36";
;
PART_NUMBER"CS03322FB03"
TOLERANCE"1%"
VALUE"33.2"
MATERIAL"CHIP"
WATTAGE"1/16W"
PACK_TYPE"0402LF"
$LOCATION"R3056"
CDS_LIB"pure_quanta"
CDS_LOCATION"R3056"
$SEC"1"
CDS_SEC"1";
"B"
$PN"2"66;
"A"
$PN"1"50;
%"Q_RES"
"1","(-9950,1625)","0","pure_quanta","I37";
;
PART_NUMBER"CS00002JB13"
TOLERANCE"5%"
MATERIAL"CHIP"
VALUE"0"
$LOCATION"R483"
WATTAGE"1/16W"
PACK_TYPE"0402LF"
CDS_LIB"pure_quanta"
$LOCATION"R483"
CDS_LOCATION"R483"
$SEC"1"
CDS_SEC"1";
"B"
$PN"2"28;
"A"
$PN"1"52;
%"NX3L2267GM"
"1","(-8425,-200)","0","pure_quanta","I38";
;
PART_NUMBER"AL002267000"
PART_TYPE"SMLF"
VALUE"NX3L2267GM"
MATERIAL"IC"
$LOCATION"U97"
SEC_TYPE""
CDS_LIB"pure_quanta"
NEEDS_NO_SIZE"TRUE"
CDS_LMAN_SYM_OUTLINE"-250,400,250,-400"
CDS_LOCATION"U97"
SEC"1";
"2Y0"
$PN"3"34;
"1S"
$PN"8"23;
"1Z"
$PN"9"31;
"2Y1"
$PN"4"36;
"2S"
$PN"7"23;
"1Y1"
$PN"2"37;
"GND"
$PN"5"14;
"1Y0"
$PN"1"35;
"2Z"
$PN"6"30;
"VCC"
$PN"10"9;
%"UNIVERSAL_GND"
"1","(-8950,-675)","0","logical_power","I39";
;
HDL_POWER"GND"
CDS_LIB"logical_power";
"A"14;
%"UNIVERSAL_POWER"
"1","(-10850,2450)","0","logical_power","I42";
;
HDL_POWER"P3V3_AUX"
CDS_LIB"logical_power";
"A"3;
%"Q_CAP"
"1","(-10700,2200)","0","pure_quanta","I43";
;
PART_NUMBER"CH5104KEB02"
MATERIAL"X6S"
VALUE"1UF"
VOLTAGE"25V"
TOLERANCE"10%"
PACK_TYPE"C0402"
$LOCATION"C1290"
CDS_LIB"pure_quanta"
$LOCATION"C1290"
CDS_LOCATION"C1290"
$SEC"1"
CDS_SEC"1";
"B"
$PN"2"17;
"A"
$PN"1"3;
%"UNIVERSAL_GND"
"1","(-10700,1975)","0","logical_power","I44";
;
CDS_LIB"logical_power"
HDL_POWER"GND";
"A"17;
%"GTL2014PW"
"1","(-11350,1575)","2","pure_quanta","I45";
;
PART_NUMBER"AL002014K01"
PART_TYPE"SMLF"
MATERIAL"IC"
VALUE"GTL2014PW"
$LOCATION"U83"
NEEDS_NO_SIZE"TRUE"
CDS_LMAN_SYM_OUTLINE"-250,350,250,-350"
CDS_LIB"pure_quanta"
SEC_TYPE""
$LOCATION"U83"
CDS_LOCATION"U83"
SEC"1";
"VCC"
$PN"14"3;
"VREF"
$PN"4"65;
"DIR"
$PN"1"49;
"A0"
$PN"13"33;
"A1"
$PN"12"50;
"A2"
$PN"10"51;
"A3"
$PN"9"52;
"GND_0"
$PN"7"16;
"GND_1"
$PN"8"16;
"GND_2"
$PN"11"16;
"B3"
$PN"6"41;
"B2"
$PN"5"53;
"B1"
$PN"3"40;
"B0"
$PN"2"54;
%"UNIVERSAL_GND"
"1","(-11875,1175)","0","logical_power","I46";
;
HDL_POWER"GND"
CDS_LIB"logical_power";
"A"16;
%"Q_RES"
"2","(-12425,1250)","0","pure_quanta","I47";
;
PART_NUMBER"CS21002FB06"
TOLERANCE"1%"
VALUE"1K"
PACK_TYPE"0402LF"
MATERIAL"CHIP"
WATTAGE"1/16W"
$LOCATION"R1369"
CDS_LIB"pure_quanta"
CDS_LOCATION"R1369"
$SEC"1"
CDS_SEC"1";
"A"
$PN"1"54;
"B"
$PN"2"15;
%"Q_RES"
"2","(-12650,1250)","0","pure_quanta","I48";
;
PART_NUMBER"CS21002FB06"
MATERIAL"CHIP"
TOLERANCE"1%"
VALUE"1K"
WATTAGE"1/16W"
PACK_TYPE"0402LF"
$LOCATION"R1368"
CDS_LIB"pure_quanta"
CDS_LOCATION"R1368"
$SEC"1"
CDS_SEC"1";
"A"
$PN"1"53;
"B"
$PN"2"15;
%"UNIVERSAL_GND"
"1","(-12650,975)","0","logical_power","I49";
;
CDS_LIB"logical_power"
HDL_POWER"GND";
"A"15;
%"UNIVERSAL_POWER"
"1","(-11875,575)","0","logical_power","I54";
;
HDL_POWER"P3V3_AUX"
CDS_LIB"logical_power";
"A"1;
%"Q_CAP"
"1","(-11725,300)","0","pure_quanta","I55";
;
PART_NUMBER"CH4104K1B00"
PACK_TYPE"0402"
TOLERANCE"10%"
VOLTAGE"25V"
MATERIAL"X7R"
VALUE"0.1UF"
$LOCATION"C1321"
CDS_LIB"pure_quanta"
CDS_LOCATION"C1321"
$SEC"1"
CDS_SEC"1";
"B"
$PN"2"11;
"A"
$PN"1"1;
%"UNIVERSAL_GND"
"1","(-11725,100)","0","logical_power","I56";
;
CDS_LIB"logical_power"
HDL_POWER"GND";
"A"11;
%"Q_RES"
"1","(-13050,3050)","0","pure_quanta","I57";
;
PART_NUMBER"CS00002JB13"
MATERIAL"CHIP"
TOLERANCE"5%"
VALUE"0"
$LOCATION"R482"
PACK_TYPE"0402LF"
WATTAGE"1/16W"
CDS_LIB"pure_quanta"
$LOCATION"R482"
CDS_LOCATION"R482"
$SEC"1"
CDS_SEC"1";
"B"
$PN"2"46;
"A"
$PN"1"42;
%"Q_RES"
"1","(-13050,3150)","0","pure_quanta","I58";
;
PART_NUMBER"CS00002JB13"
MATERIAL"CHIP"
VALUE"0"
TOLERANCE"5%"
$LOCATION"R481"
CDS_LIB"pure_quanta"
WATTAGE"1/16W"
PACK_TYPE"0402LF"
$LOCATION"R481"
CDS_LOCATION"R481"
$SEC"1"
CDS_SEC"1";
"B"
$PN"2"47;
"A"
$PN"1"44;
%"Q_RES"
"1","(-13050,3200)","0","pure_quanta","I59";
;
PART_NUMBER"CS00002JB13"
MATERIAL"CHIP"
PACK_TYPE"0402LF"
TOLERANCE"5%"
VALUE"0"
WATTAGE"1/16W"
$LOCATION"R480"
CDS_LIB"pure_quanta"
$LOCATION"R480"
CDS_LOCATION"R480"
$SEC"1"
CDS_SEC"1";
"B"
$PN"2"48;
"A"
$PN"1"45;
%"UNIVERSAL_POWER"
"1","(-7925,3975)","0","logical_power","I6";
;
HDL_POWER"P3V3_AUX"
CDS_LIB"logical_power";
"A"10;
%"Q_RES"
"1","(-13075,1625)","0","pure_quanta","I64";
;
PART_NUMBER"CS11002FB07"
MATERIAL"CHIP"
VALUE"100"
TOLERANCE"1%"
WATTAGE"1/16W"
PACK_TYPE"0402LF"
$LOCATION"R1366"
CDS_LIB"pure_quanta"
CDS_LOCATION"R1366"
$SEC"1"
CDS_SEC"1";
"B"
$PN"2"41;
"A"
$PN"1"39;
%"Q_RES"
"1","(-13075,1525)","0","pure_quanta","I65";
;
PART_NUMBER"CS11002FB07"
MATERIAL"CHIP"
TOLERANCE"1%"
VALUE"100"
$LOCATION"R1367"
WATTAGE"1/16W"
PACK_TYPE"0402LF"
CDS_LIB"pure_quanta"
CDS_LOCATION"R1367"
$SEC"1"
CDS_SEC"1";
"B"
$PN"2"40;
"A"
$PN"1"38;
%"NX3L2267GM"
"1","(-12475,-200)","0","pure_quanta","I68";
;
PART_NUMBER"AL002267000"
MATERIAL"IC"
PART_TYPE"SMLF"
VALUE"NX3L2267GM"
$LOCATION"U96"
SEC_TYPE""
CDS_LIB"pure_quanta"
NEEDS_NO_SIZE"TRUE"
CDS_LMAN_SYM_OUTLINE"-250,400,250,-400"
CDS_LOCATION"U96"
SEC"1";
"2Y0"
$PN"3"24;
"1S"
$PN"8"23;
"1Z"
$PN"9"29;
"2Y1"
$PN"4"26;
"2S"
$PN"7"23;
"1Y1"
$PN"2"25;
"GND"
$PN"5"12;
"1Y0"
$PN"1"27;
"2Z"
$PN"6"32;
"VCC"
$PN"10"1;
%"UNIVERSAL_GND"
"1","(-13000,-675)","0","logical_power","I69";
;
CDS_LIB"logical_power"
HDL_POWER"GND";
"A"12;
%"Q_RES"
"2","(-7925,3575)","0","pure_quanta","I7";
;
PART_NUMBER"CS21002FB06"
PACK_TYPE"0402LF"
MATERIAL"CHIP"
VALUE"1K"
TOLERANCE"1%"
WATTAGE"1/16W"
$LOCATION"R1381"
CDS_LIB"pure_quanta"
CDS_LOCATION"R1381"
$SEC"1"
CDS_SEC"1";
"A"
$PN"1"10;
"B"
$PN"2"63;
%"UNIVERSAL_POWER"
"1","(-14125,-275)","0","logical_power","I76";
;
HDL_POWER"P3V3_AUX"
CDS_LIB"logical_power";
"A"2;
%"Q_RES"
"2","(-14075,-975)","0","pure_quanta","I77";
;
PART_NUMBER"CS21002FB06"
VALUE"1K"
MATERIAL"EMPTY"
WATTAGE"1/16W"
TOLERANCE"1%"
PACK_TYPE"0402LF"
$LOCATION"R1814"
CDS_LIB"pure_quanta"
CDS_LOCATION"R1814"
$SEC"1"
CDS_SEC"1";
"A"
$PN"1"23;
"B"
$PN"2"13;
%"UNIVERSAL_GND"
"1","(-14075,-1225)","0","logical_power","I78";
;
CDS_LIB"logical_power"
HDL_POWER"GND";
"A"13;
%"Q_RES"
"2","(-14125,-500)","0","pure_quanta","I79";
;
PART_NUMBER"CS31002FB08"
PACK_TYPE"0402LF"
VALUE"10K"
TOLERANCE"1%"
WATTAGE"1/16W"
MATERIAL"EMPTY"
$LOCATION"R1813"
CDS_LIB"pure_quanta"
CDS_LOCATION"R1813"
$SEC"1"
CDS_SEC"1";
"A"
$PN"1"2;
"B"
$PN"2"23;
%"UNIVERSAL_GND"
"1","(-9000,3225)","2","logical_power","I8";
;
HDL_POWER"GND"
CDS_LIB"logical_power";
"A"21;
%"Q_RES"
"1","(-8625,2925)","0","pure_quanta","I80";
;
PART_NUMBER"CS00002JB13"
MATERIAL"EMPTY"
TOLERANCE"5%"
WATTAGE"1/16W"
PACK_TYPE"0402LF"
VALUE"0"
$LOCATION"R1832"
CDS_LIB"pure_quanta"
CDS_LOCATION"R1832"
$SEC"1"
CDS_SEC"1";
"B"
$PN"2"61;
"A"
$PN"1"67;
%"Q_RES"
"1","(-8650,1400)","0","pure_quanta","I82";
;
PART_NUMBER"CS00002JB13"
TOLERANCE"5%"
PACK_TYPE"0402LF"
WATTAGE"1/16W"
MATERIAL"EMPTY"
VALUE"0"
$LOCATION"R1831"
CDS_LIB"pure_quanta"
CDS_LOCATION"R1831"
$SEC"1"
CDS_SEC"1";
"B"
$PN"2"59;
"A"
$PN"1"66;
%"UNIVERSAL_POWER"
"1","(-8400,3975)","0","logical_power","I86";
;
HDL_POWER"P3V3_AUX"
CDS_LIB"logical_power";
"A"8;
%"Q_RES"
"2","(-8400,3575)","0","pure_quanta","I87";
;
PART_NUMBER"CS21002FB06"
MATERIAL"CHIP"
WATTAGE"1/16W"
TOLERANCE"1%"
PACK_TYPE"0402LF"
VALUE"1K"
$LOCATION"R2506"
CDS_LIB"pure_quanta"
CDS_LOCATION"R2506"
$SEC"1"
CDS_SEC"1";
"A"
$PN"1"8;
"B"
$PN"2"64;
%"Q_RES"
"2","(-8175,3575)","0","pure_quanta","I88";
;
PART_NUMBER"CS21002FB06"
VALUE"1K"
MATERIAL"CHIP"
PACK_TYPE"0402LF"
TOLERANCE"1%"
WATTAGE"1/16W"
$LOCATION"R2507"
CDS_LIB"pure_quanta"
CDS_LOCATION"R2507"
$SEC"1"
CDS_SEC"1";
"A"
$PN"1"8;
"B"
$PN"2"62;
%"Q_RES"
"1","(-9400,3300)","0","pure_quanta","I89";
;
PART_NUMBER"CS21002FB06"
MATERIAL"EMPTY"
VALUE"1K"
TOLERANCE"1%"
$LOCATION"R2514"
PACK_TYPE"0402LF"
WATTAGE"1/16W"
CDS_LIB"pure_quanta"
CDS_LOCATION"R2514"
$SEC"1"
CDS_SEC"1";
"B"
$PN"2"21;
"A"
$PN"1"60;
%"UNIVERSAL_POWER"
"1","(-10100,4000)","0","logical_power","I9";
;
HDL_POWER"P3V3_AUX"
CDS_LIB"logical_power";
"A"6;
%"Q_RES"
"1","(-9450,1725)","0","pure_quanta","I90";
;
PART_NUMBER"CS00002JB13"
TOLERANCE"5%"
MATERIAL"CHIP"
VALUE"0"
$LOCATION"R2513"
CDS_LIB"pure_quanta"
WATTAGE"1/16W"
PACK_TYPE"0402LF"
CDS_LOCATION"R2513"
$SEC"1"
CDS_SEC"1";
"B"
$PN"2"20;
"A"
$PN"1"49;
%"Q_RES"
"2","(-10125,2175)","0","pure_quanta","I91";
;
PART_NUMBER"CS04992FB07"
TOLERANCE"1%"
VALUE"49.9"
WATTAGE"1/16W"
MATERIAL"CHIP"
PACK_TYPE"0402LF"
$LOCATION"R2512"
CDS_LIB"pure_quanta"
CDS_LOCATION"R2512"
$SEC"1"
CDS_SEC"1";
"A"
$PN"1"5;
"B"
$PN"2"65;
%"UNIVERSAL_POWER"
"1","(-10125,2525)","0","logical_power","I92";
;
HDL_POWER"P1V05_PCH_AUX"
CDS_LIB"logical_power";
"A"5;
%"Q_CAP"
"2","(-9450,2075)","0","pure_quanta","I93";
;
PART_NUMBER"CH4104K1B00"
TOLERANCE"10%"
VALUE"0.1UF"
VOLTAGE"25V"
PACK_TYPE"0402"
MATERIAL"X7R"
$LOCATION"C1664"
CDS_LIB"pure_quanta"
CDS_LOCATION"C1664"
$SEC"1"
CDS_SEC"1";
"A"
$PN"1"65;
"B"
$PN"2"20;
END.
